# BASEBOARD_FAB2 (Tioga Pass) — schematic netlist excerpt (pin names and nets, part order shuffled) for the footprints in the layout excerpt that follows; sources: Cadence DE-HDL packaged netlist, KiCad conversion of Wiwynn_Tioga_Pass_MB.brd

C3E1  CAP_A  22.0UF 4V 20% X6S  pkg 0603V  page 214 : A = PVCCIO_CPU1 ; B = GND
R1C18  RES  2.26K 1.0% EMPTY  pkg 0402  page 206 : A = P3V3_STBY ; B = PU_VR_PVCCIN_CPU1_IMON
C5A17  CAP_A  47UF 4V 20% X5R  pkg 0603V  page 220 : A = PVDDQ_DEF ; B = GND

(kicad_pcb
	(version 20260206)
	(generator "pcbnew")
	(generator_version "10.0")
	(general
		(thickness 1.6)
		(legacy_teardrops no)
	)
	(paper "A4")
	(title_block
		(title "Wiwynn_Tioga_Pass_MB.brd")
		(comment 1 "Tioga Pass / footprints 590-592 of 4770")
	)
	(layers
		(0 "F.Cu" signal "TOP")
		(4 "In1.Cu" signal "L2GND")
		(6 "In2.Cu" signal "L3")
		(8 "In3.Cu" signal "L4GND")
		(10 "In4.Cu" signal "L5")
		(12 "In5.Cu" signal "L6GND")
		(14 "In6.Cu" signal "L7VCC")
		(16 "In7.Cu" signal "L8VCC")
		(18 "In8.Cu" signal "L9GND")
		(20 "In9.Cu" signal "L10")
		(22 "In10.Cu" signal "L11GND")
		(24 "In11.Cu" signal "L12")
		(26 "In12.Cu" signal "L13GND")
		(2 "B.Cu" signal "BOTTOM")
		(9 "F.Adhes" user "F.Adhesive")
		(11 "B.Adhes" user "B.Adhesive")
		(13 "F.Paste" user "Package Geometry/Pastemask Top")
		(15 "B.Paste" user "Package Geometry/Pastemask Bottom")
		(5 "F.SilkS" user "Ref Des/Silkscreen Top")
		(7 "B.SilkS" user "Ref Des/Silkscreen Bottom")
		(1 "F.Mask" user "Board Geometry/Soldermask Top")
		(3 "B.Mask" user "Board Geometry/Soldermask Bottom")
		(17 "Dwgs.User" user "User.Drawings")
		(19 "Cmts.User" user "User.Comments")
		(21 "Eco1.User" user "User.Eco1")
		(23 "Eco2.User" user "User.Eco2")
		(25 "Edge.Cuts" user "Board Geometry/Outline")
		(27 "Margin" user)
		(31 "F.CrtYd" user "Package Geometry/Place Bound Top")
		(29 "B.CrtYd" user "Package Geometry/Place Bound Bottom")
		(35 "F.Fab" user "Ref Des/Assembly Top")
		(33 "B.Fab" user "Ref Des/Assembly Bottom")
	)
	(footprint ""
		(layer "F.Cu")
		(at 22.4282 -98.19894)
		(property "Reference" "R1C18"
			(at 0 0 0)
			(layer "F.SilkS")
			(hide yes)
			(effects
				(font
					(size 1.27 1.27)
				)
			)
		)
		(property "Value" ""
			(at 0 0 0)
			(layer "F.Fab")
			(effects
				(font
					(size 1.27 1.27)
				)
			)
		)
		(duplicate_pad_numbers_are_jumpers no)
		(fp_rect
			(start -0.2794 0.9906)
			(end 0.2794 -0.1016)
			(stroke
				(width 0)
				(type default)
			)
			(fill no)
			(layer "F.CrtYd")
		)
		(fp_line
			(start -0.2794 -0.1016)
			(end -0.2794 0.9906)
			(stroke
				(width 0.1)
				(type default)
			)
			(layer "F.Fab")
		)
		(fp_line
			(start -0.2794 0.9906)
			(end 0.2794 0.9906)
			(stroke
				(width 0.1)
				(type default)
			)
			(layer "F.Fab")
		)
		(fp_line
			(start 0.2794 -0.1016)
			(end -0.2794 -0.1016)
			(stroke
				(width 0.1)
				(type default)
			)
			(layer "F.Fab")
		)
		(fp_line
			(start 0.2794 0.9906)
			(end 0.2794 -0.1016)
			(stroke
				(width 0.1)
				(type default)
			)
			(layer "F.Fab")
		)
		(pad "1" smd rect
			(at 0 0)
			(size 0.508 0.508)
			(layers "F.Cu" "F.Mask" "F.Paste")
			(net "P3V3_STBY")
		)
		(pad "2" smd rect
			(at 0 0.889)
			(size 0.508 0.508)
			(layers "F.Cu" "F.Mask" "F.Paste")
			(net "PU_VR_PVCCIN_CPU1_IMON")
		)
		(zone
			(layer "F.Cu")
			(hatch none 0.5)
			(connect_pads
				(clearance 0)
			)
			(min_thickness 0.25)
			(keepout
				(tracks not_allowed)
				(vias allowed)
				(pads allowed)
				(copperpour not_allowed)
				(footprints allowed)
			)
			(placement
				(enabled no)
				(sheetname "")
			)
			(fill
				(thermal_gap 0.5)
				(thermal_bridge_width 0.5)
				(island_removal_mode 0)
			)
			(polygon
				(pts
					(xy 22.1742 -97.56394) (xy 22.6822 -97.56394) (xy 22.6822 -97.94494) (xy 22.1742 -97.94494)
				)
			)
		)
		(zone
			(layer "F.Cu")
			(hatch none 0.5)
			(connect_pads
				(clearance 0)
			)
			(min_thickness 0.25)
			(keepout
				(tracks allowed)
				(vias not_allowed)
				(pads allowed)
				(copperpour not_allowed)
				(footprints allowed)
			)
			(placement
				(enabled no)
				(sheetname "")
			)
			(fill
				(thermal_gap 0.5)
				(thermal_bridge_width 0.5)
				(island_removal_mode 0)
			)
			(polygon
				(pts
					(xy 22.1742 -97.56394) (xy 22.6822 -97.56394) (xy 22.6822 -97.94494) (xy 22.1742 -97.94494)
				)
			)
		)
	)
	(footprint ""
		(layer "F.Cu")
		(at 269.559532 -140.208 90)
		(property "Reference" "C5A17"
			(at 1.848866 0.752348 90)
			(unlocked yes)
			(layer "F.SilkS")
			(effects
				(font
					(size 1.27 0.9652)
					(thickness 0.1524)
				)
			)
		)
		(property "Value" ""
			(at 0 0 90)
			(layer "F.Fab")
			(effects
				(font
					(size 1.27 1.27)
				)
			)
		)
		(duplicate_pad_numbers_are_jumpers no)
		(fp_rect
			(start -0.500126 1.598422)
			(end 0.500126 -0.201422)
			(stroke
				(width 0)
				(type default)
			)
			(fill no)
			(layer "F.CrtYd")
		)
		(fp_line
			(start 0.500126 -0.201422)
			(end 0.500126 1.598422)
			(stroke
				(width 0.1)
				(type default)
			)
			(layer "F.Fab")
		)
		(fp_line
			(start -0.500126 -0.201422)
			(end 0.500126 -0.201422)
			(stroke
				(width 0.1)
				(type default)
			)
			(layer "F.Fab")
		)
		(fp_line
			(start 0.500126 1.598422)
			(end -0.500126 1.598422)
			(stroke
				(width 0.1)
				(type default)
			)
			(layer "F.Fab")
		)
		(fp_line
			(start -0.500126 1.598422)
			(end -0.500126 -0.201422)
			(stroke
				(width 0.1)
				(type default)
			)
			(layer "F.Fab")
		)
		(pad "1" smd rect
			(at 0 0)
			(size 0.889 0.9906)
			(layers "F.Cu" "F.Mask" "F.Paste")
			(net "PVDDQ_DEF")
		)
		(pad "2" smd rect
			(at 0 1.397)
			(size 0.889 0.9906)
			(layers "F.Cu" "F.Mask" "F.Paste")
			(net "GND")
		)
		(zone
			(layer "F.Cu")
			(hatch none 0.5)
			(connect_pads
				(clearance 0)
			)
			(min_thickness 0.25)
			(keepout
				(tracks not_allowed)
				(vias allowed)
				(pads allowed)
				(copperpour not_allowed)
				(footprints allowed)
			)
			(placement
				(enabled no)
				(sheetname "")
			)
			(fill
				(thermal_gap 0.5)
				(thermal_bridge_width 0.5)
				(island_removal_mode 0)
			)
			(polygon
				(pts
					(xy 270.512032 -139.7127) (xy 270.512032 -140.7033) (xy 270.004032 -140.7033) (xy 270.004032 -139.7127)
				)
			)
		)
		(zone
			(layer "F.Cu")
			(hatch none 0.5)
			(connect_pads
				(clearance 0)
			)
			(min_thickness 0.25)
			(keepout
				(tracks allowed)
				(vias not_allowed)
				(pads allowed)
				(copperpour not_allowed)
				(footprints allowed)
			)
			(placement
				(enabled no)
				(sheetname "")
			)
			(fill
				(thermal_gap 0.5)
				(thermal_bridge_width 0.5)
				(island_removal_mode 0)
			)
			(polygon
				(pts
					(xy 270.512032 -139.7127) (xy 270.512032 -140.7033) (xy 270.004032 -140.7033) (xy 270.004032 -139.7127)
				)
			)
		)
	)
	(footprint ""
		(layer "F.Cu")
		(at 161.798 -59.309 180)
		(property "Reference" "C3E1"
			(at 0 0 180)
			(layer "F.SilkS")
			(hide yes)
			(effects
				(font
					(size 1.27 1.27)
				)
			)
		)
		(property "Value" ""
			(at 0 0 180)
			(layer "F.Fab")
			(effects
				(font
					(size 1.27 1.27)
				)
			)
		)
		(duplicate_pad_numbers_are_jumpers no)
		(fp_poly
			(pts
				(xy -0.4953 -0.2032) (xy 0.4953 -0.2032) (xy 0.4953 1.6002) (xy -0.4953 1.6002)
			)
			(stroke
				(width 0)
				(type default)
			)
			(fill no)
			(layer "F.CrtYd")
		)
		(fp_line
			(start 0.4953 1.6002)
			(end -0.4953 1.6002)
			(stroke
				(width 0.1)
				(type default)
			)
			(layer "F.Fab")
		)
		(fp_line
			(start 0.4953 -0.2032)
			(end 0.4953 1.6002)
			(stroke
				(width 0.1)
				(type default)
			)
			(layer "F.Fab")
		)
		(fp_line
			(start -0.4953 1.6002)
			(end -0.4953 -0.2032)
			(stroke
				(width 0.1)
				(type default)
			)
			(layer "F.Fab")
		)
		(fp_line
			(start -0.4953 -0.2032)
			(end 0.4953 -0.2032)
			(stroke
				(width 0.1)
				(type default)
			)
			(layer "F.Fab")
		)
		(pad "1" smd rect
			(at 0 0 180)
			(size 0.762 0.889)
			(layers "F.Cu" "F.Mask" "F.Paste")
			(net "PVCCIO_CPU1")
		)
		(pad "2" smd rect
			(at 0 1.397 180)
			(size 0.762 0.889)
			(layers "F.Cu" "F.Mask" "F.Paste")
			(net "GND")
		)
		(zone
			(layer "F.Cu")
			(hatch none 0.5)
			(connect_pads
				(clearance 0)
			)
			(min_thickness 0.25)
			(keepout
				(tracks not_allowed)
				(vias allowed)
				(pads allowed)
				(copperpour not_allowed)
				(footprints allowed)
			)
			(placement
				(enabled no)
				(sheetname "")
			)
			(fill
				(thermal_gap 0.5)
				(thermal_bridge_width 0.5)
				(island_removal_mode 0)
			)
			(polygon
				(pts
					(xy 162.179 -59.7535) (xy 161.417 -59.7535) (xy 161.417 -60.2615) (xy 162.179 -60.2615)
				)
			)
		)
	)
)
